FILE_TYPE = MULTI_PHYS_TABLE;

PART 'CONN_HDR_2X2_M_S_SMT'
CLASS = IO 

{========================================================================================}
:CLS_PN             = JEDEC_TYPE            |ALT_SYMBOLS             |DESCRIPTION                  ;
{========================================================================================}
 'G200-10686-01'(!)      = 'S_M_H_2X2_S_P100_V3'  |'(S_M_H_2X2_S_P100_V3)'  |'CON, HEADER, 4PIN, 2 X 2 DUAL ROHS, 2.54MM PITCH, SMT'
 'G200-10238-01'(!)      = 'S_M_H_2X2_S_P100'     |'(S_M_H_2X2_S_P100)'     |'CON,4P,2X2,2.54MM,VERT,SMT'  
 'G200-12149-01'(!)      = 'S_M_H_2X2_S_P100_V4'  |'(S_M_H_2X2_S_P100_V4)'     |'CON,2X2,2.54MM PITCH,H 7.8MM,VT,SMT' 
 'A200-00003-IB'(!)      = 'S_M_H_2X2_S_P0787'  |'(S_M_H_2X2_S_P0787)'     |'CONN,4P,2X2,2MM PITCH,V/T SHROUNDED,SMT'
 'G200-12631-01'(!)      = 'S_M_H_2X2_S_P0787'  |'(S_M_H_2X2_S_P0787)'     |'CONN,4P,2X2,2MM PITCH,V/T SHROUNDED,30U GOLD,WITH LOCKING WINDOW,SMT'
 'G200-12821-01'         = 'S_M_H_2X2_S_P050'   |'(S_M_H_2X2_S_P050)'      |'CON,4P,2X2,1.27MM PITCH,HEADER,VERT,SMT'


END_PART

END.


